(kicad_pcb
	(version 20221018)
	(generator pcbnew)
	(general
    (thickness 1.518)
  )
	(paper "A4")
	(title_block
    (title "Kria K26 Devboard")
    (date "2024-03-26")
    (rev "1.2.5")
    (comment 1 "www.antmicro.com")
    (comment 2 "Antmicro Ltd.")
		(comment 9 "footprints 182-184 of 660")
	)
	(layers
    (0 "F.Cu" mixed)
    (1 "In1.Cu" power)
    (2 "In2.Cu" mixed)
    (3 "In3.Cu" power)
    (4 "In4.Cu" mixed)
    (5 "In5.Cu" power)
    (6 "In6.Cu" mixed)
    (31 "B.Cu" power)
    (32 "B.Adhes" user "B.Adhesive")
    (33 "F.Adhes" user "F.Adhesive")
    (34 "B.Paste" user)
    (35 "F.Paste" user)
    (36 "B.SilkS" user "B.Silkscreen")
    (37 "F.SilkS" user "F.Silkscreen")
    (38 "B.Mask" user)
    (39 "F.Mask" user)
    (40 "Dwgs.User" user "User.Drawings")
    (41 "Cmts.User" user "User.Comments")
    (42 "Eco1.User" user "User.Eco1")
    (43 "Eco2.User" user "User.Eco2")
    (44 "Edge.Cuts" user)
    (45 "Margin" user)
    (46 "B.CrtYd" user "B.Courtyard")
    (47 "F.CrtYd" user "F.Courtyard")
    (48 "B.Fab" user)
    (49 "F.Fab" user)
  )
	(footprint "kria-k26-devboard-footprints:R_0402_1005Metric" (layer "F.Cu")
    (at 141.785 90.2 180)
    (descr "Resistor SMD 0402")
    (tags "resistor SMD 0402")
    (property "Author" "Antmicro")
    (property "License" "Apache-2.0")
    (property "MPN" "CR0402-FX-4701GLF")
    (property "Manufacturer" "Bourns")
    (property "Sheetfile" "eth.kicad_sch")
    (property "Sheetname" "Ethernet")
    (property "Tolerance" "1%")
    (property "Val" "4k7")
    (property "ki_description" "4k7 resistor in 0402 package with 1% tolerance")
    (attr smd)
    (fp_text reference "R75" (at 2.995 -0.41 180) (layer "F.SilkS")
        (effects (font (size 0.7 0.7) (thickness 0.15)) (justify left bottom))
    )
    (fp_text value "R_4k7_0402" (at 0 1.4 180) (layer "F.Fab") hide
        (effects (font (size 0.7 0.7) (thickness 0.15)) (justify left bottom))
    )
    (fp_text user "Author: Antmicro" (at -0.95 4.169 180) (layer "F.Fab") hide
        (effects (font (size 0.7 0.7) (thickness 0.15)) (justify left bottom))
    )
    (fp_text user "${REFERENCE}" (at -0.95 3.168 180) (layer "F.Fab") hide
        (effects (font (size 0.7 0.7) (thickness 0.15)) (justify left bottom))
    )
    (fp_text user "License: Apache-2.0" (at -0.95 5.169 180) (layer "F.Fab") hide
        (effects (font (size 0.7 0.7) (thickness 0.15)) (justify left bottom))
    )
    (fp_rect (start -0.93 -0.47) (end 0.93 0.47)
      (stroke (width 0.05) (type solid)) (fill none) (layer "F.CrtYd"))
    (fp_rect (start -0.5 -0.25) (end 0.5 0.25)
      (stroke (width 0.15) (type solid)) (fill none) (layer "F.Fab"))
    (pad "1" smd roundrect (at -0.485 0 180) (size 0.59 0.64) (layers "F.Cu" "F.Paste" "F.Mask") (roundrect_rratio 0.25)
      (net 674 "Net-(U30-JTAG_TMS)") (pintype "passive"))
    (pad "2" smd roundrect (at 0.485 0 180) (size 0.59 0.64) (layers "F.Cu" "F.Paste" "F.Mask") (roundrect_rratio 0.25)
      (net 17 "PS_1V8") (pintype "passive"))
  )
	(footprint "kria-k26-devboard-footprints:C_0402_1005Metric" (layer "F.Cu")
    (at 149.245911 93.839035 -90)
    (descr "Capacitor SMD 0402")
    (tags "capacitor SMD 0402")
    (property "Author" "Antmicro")
    (property "Dielectric" "X5R")
    (property "License" "Apache-2.0")
    (property "MPN" "GRM155R61H104KE14D")
    (property "Manufacturer" "Murata")
    (property "Sheetfile" "eth.kicad_sch")
    (property "Sheetname" "Ethernet")
    (property "Val" "100n")
    (property "Voltage" "50V")
    (property "ki_description" " ")
    (attr smd)
    (fp_text reference "C107" (at 3.69 -0.41 -90) (layer "F.SilkS")
        (effects (font (size 0.7 0.7) (thickness 0.15)) (justify left bottom))
    )
    (fp_text value "C_100n_0402" (at 0 1.4 -90) (layer "F.Fab") hide
        (effects (font (size 0.7 0.7) (thickness 0.15)) (justify left bottom))
    )
    (fp_text user "License: Apache-2.0" (at -0.932 5.17 -90) (layer "F.Fab") hide
        (effects (font (size 0.7 0.7) (thickness 0.15)) (justify left bottom))
    )
    (fp_text user "Author: Antmicro" (at -0.932 4.17 -90) (layer "F.Fab") hide
        (effects (font (size 0.7 0.7) (thickness 0.15)) (justify left bottom))
    )
    (fp_text user "${REFERENCE}" (at -0.932 3.168 -90) (layer "F.Fab") hide
        (effects (font (size 0.7 0.7) (thickness 0.15)) (justify left bottom))
    )
    (fp_rect (start -0.94 -0.47) (end 0.94 0.47)
      (stroke (width 0.05) (type solid)) (fill none) (layer "F.CrtYd"))
    (fp_rect (start -0.499 -0.249) (end 0.499 0.249)
      (stroke (width 0.15) (type solid)) (fill none) (layer "F.Fab"))
    (pad "1" smd roundrect (at -0.484 0 270) (size 0.59 0.64) (layers "F.Cu" "F.Paste" "F.Mask") (roundrect_rratio 0.25)
      (net 19 "PS_1V0") (pintype "passive"))
    (pad "2" smd roundrect (at 0.484 0 270) (size 0.59 0.64) (layers "F.Cu" "F.Paste" "F.Mask") (roundrect_rratio 0.25)
      (net 1 "GND") (pintype "passive"))
  )
	(footprint "kria-k26-devboard-footprints:C_0402_1005Metric" (layer "F.Cu")
    (at 154.106621 90.117588)
    (descr "Capacitor SMD 0402")
    (tags "capacitor SMD 0402")
    (property "Author" "Antmicro")
    (property "Dielectric" "X5R")
    (property "License" "Apache-2.0")
    (property "MPN" "GRM155R61H104KE14D")
    (property "Manufacturer" "Murata")
    (property "Sheetfile" "eth.kicad_sch")
    (property "Sheetname" "Ethernet")
    (property "Val" "100n")
    (property "Voltage" "50V")
    (property "ki_description" " ")
    (attr smd)
    (fp_text reference "C101" (at -1.126621 1.262412) (layer "F.SilkS")
        (effects (font (size 0.7 0.7) (thickness 0.15)) (justify left bottom))
    )
    (fp_text value "C_100n_0402" (at 0 1.4) (layer "F.Fab") hide
        (effects (font (size 0.7 0.7) (thickness 0.15)) (justify left bottom))
    )
    (fp_text user "Author: Antmicro" (at -0.932 4.17) (layer "F.Fab") hide
        (effects (font (size 0.7 0.7) (thickness 0.15)) (justify left bottom))
    )
    (fp_text user "${REFERENCE}" (at -0.932 3.168) (layer "F.Fab") hide
        (effects (font (size 0.7 0.7) (thickness 0.15)) (justify left bottom))
    )
    (fp_text user "License: Apache-2.0" (at -0.932 5.17) (layer "F.Fab") hide
        (effects (font (size 0.7 0.7) (thickness 0.15)) (justify left bottom))
    )
    (fp_rect (start -0.94 -0.47) (end 0.94 0.47)
      (stroke (width 0.05) (type solid)) (fill none) (layer "F.CrtYd"))
    (fp_rect (start -0.499 -0.249) (end 0.499 0.249)
      (stroke (width 0.15) (type solid)) (fill none) (layer "F.Fab"))
    (pad "1" smd roundrect (at -0.484 0) (size 0.59 0.64) (layers "F.Cu" "F.Paste" "F.Mask") (roundrect_rratio 0.25)
      (net 17 "PS_1V8") (pintype "passive"))
    (pad "2" smd roundrect (at 0.484 0) (size 0.59 0.64) (layers "F.Cu" "F.Paste" "F.Mask") (roundrect_rratio 0.25)
      (net 1 "GND") (pintype "passive"))
  )
)
